(kicad_pcb
	(version 20260206)
	(generator "pcbnew")
	(generator_version "10.0")
	(general
		(thickness 1.6)
		(legacy_teardrops no)
	)
	(paper "A4")
	(title_block
		(title "v1-chassis-manager — T6M_CM_d_v01_1031_1645.brd")
		(comment 1 "Open CloudServer (Microsoft) / footprints 196-205 of 2512")
	)
	(layers
		(0 "F.Cu" signal "TOP")
		(4 "In1.Cu" signal "GND1")
		(6 "In2.Cu" signal "IN1")
		(8 "In3.Cu" signal "VCC1")
		(10 "In4.Cu" signal "VCC2")
		(12 "In5.Cu" signal "GND2")
		(14 "In6.Cu" signal "IN2")
		(16 "In7.Cu" signal "IN3")
		(18 "In8.Cu" signal "GND3")
		(2 "B.Cu" signal "BOTTOM")
		(9 "F.Adhes" user "F.Adhesive")
		(11 "B.Adhes" user "B.Adhesive")
		(13 "F.Paste" user "Package Geometry/Pastemask Top")
		(15 "B.Paste" user "Package Geometry/Pastemask Bottom")
		(5 "F.SilkS" user "Ref Des/Silkscreen Top")
		(7 "B.SilkS" user "Ref Des/Silkscreen Bottom")
		(1 "F.Mask" user "Board Geometry/Soldermask Top")
		(3 "B.Mask" user "Board Geometry/Soldermask Bottom")
		(17 "Dwgs.User" user "User.Drawings")
		(19 "Cmts.User" user "User.Comments")
		(21 "Eco1.User" user "User.Eco1")
		(23 "Eco2.User" user "User.Eco2")
		(25 "Edge.Cuts" user "Board Geometry/Outline")
		(27 "Margin" user)
		(31 "F.CrtYd" user "Package Geometry/Place Bound Top")
		(29 "B.CrtYd" user "Package Geometry/Place Bound Bottom")
		(35 "F.Fab" user "Ref Des/Assembly Top")
		(33 "B.Fab" user "Ref Des/Assembly Bottom")
	)
	(footprint ""
		(layer "F.Cu")
		(at 83.209384 -93.763338 180)
		(property "Reference" "C109"
			(at -3.768344 -1.4351 0)
			(unlocked yes)
			(layer "F.SilkS")
			(effects
				(font
					(size 0.7874 0.5842)
					(thickness 0.1524)
				)
			)
		)
		(property "Value" ""
			(at 0 0 180)
			(layer "F.Fab")
			(effects
				(font
					(size 1.27 1.27)
				)
			)
		)
		(duplicate_pad_numbers_are_jumpers no)
		(fp_line
			(start 1.2954 0.5842)
			(end -1.2954 0.5842)
			(stroke
				(width 0.1524)
				(type default)
			)
			(layer "F.SilkS")
		)
		(fp_line
			(start 1.2954 -0.5842)
			(end 1.2954 0.5842)
			(stroke
				(width 0.1524)
				(type default)
			)
			(layer "F.SilkS")
		)
		(fp_line
			(start 0 -0.5842)
			(end 0 0.5842)
			(stroke
				(width 0.1524)
				(type default)
			)
			(layer "F.SilkS")
		)
		(fp_line
			(start -1.2954 0.5842)
			(end -1.2954 -0.5842)
			(stroke
				(width 0.1524)
				(type default)
			)
			(layer "F.SilkS")
		)
		(fp_line
			(start -1.2954 -0.5842)
			(end 1.2954 -0.5842)
			(stroke
				(width 0.1524)
				(type default)
			)
			(layer "F.SilkS")
		)
		(fp_poly
			(pts
				(xy 0.8636 -0.4572) (xy 0.8636 -0.3556) (xy 1.143 -0.3556) (xy 1.143 0.3556) (xy 0.8636 0.3556)
				(xy 0.8636 0.4572) (xy -0.8636 0.4572) (xy -0.8636 0.3556) (xy -1.143 0.3556) (xy -1.143 -0.3556)
				(xy -0.8636 -0.3556) (xy -0.8636 -0.4572)
			)
			(stroke
				(width 0)
				(type default)
			)
			(fill no)
			(layer "F.CrtYd")
		)
		(fp_line
			(start 0.884936 0.504952)
			(end -0.884936 0.504952)
			(stroke
				(width 0.1)
				(type default)
			)
			(layer "F.Fab")
		)
		(fp_line
			(start 0.884936 -0.504952)
			(end 0.884936 0.504952)
			(stroke
				(width 0.1)
				(type default)
			)
			(layer "F.Fab")
		)
		(fp_line
			(start -0.884936 0.504952)
			(end -0.884936 -0.504952)
			(stroke
				(width 0.1)
				(type default)
			)
			(layer "F.Fab")
		)
		(fp_line
			(start -0.884936 -0.504952)
			(end 0.884936 -0.504952)
			(stroke
				(width 0.1)
				(type default)
			)
			(layer "F.Fab")
		)
		(pad "1" smd rect
			(at 0.7366 0 270)
			(size 0.7112 0.8128)
			(layers "F.Cu" "F.Mask" "F.Paste")
			(net "P3V3_SUS_NODE1")
		)
		(pad "2" smd rect
			(at -0.7366 0 270)
			(size 0.7112 0.8128)
			(layers "F.Cu" "F.Mask" "F.Paste")
			(net "GND")
		)
	)
	(footprint ""
		(layer "F.Cu")
		(at 87.10676 -188.126624 -90)
		(property "Reference" "R951"
			(at -4.548886 1.93548 90)
			(unlocked yes)
			(layer "F.SilkS")
			(effects
				(font
					(size 0.7874 0.5842)
					(thickness 0.1524)
				)
				(justify left)
			)
		)
		(property "Value" ""
			(at 0 0 270)
			(layer "F.Fab")
			(effects
				(font
					(size 1.27 1.27)
				)
			)
		)
		(duplicate_pad_numbers_are_jumpers no)
		(fp_line
			(start -0.7874 0.4064)
			(end -0.7874 -0.4064)
			(stroke
				(width 0.1524)
				(type default)
			)
			(layer "F.SilkS")
		)
		(fp_line
			(start 0.7874 0.4064)
			(end -0.7874 0.4064)
			(stroke
				(width 0.1524)
				(type default)
			)
			(layer "F.SilkS")
		)
		(fp_line
			(start -0.7874 -0.4064)
			(end 0.7874 -0.4064)
			(stroke
				(width 0.1524)
				(type default)
			)
			(layer "F.SilkS")
		)
		(fp_line
			(start 0.7874 -0.4064)
			(end 0.7874 0.4064)
			(stroke
				(width 0.1524)
				(type default)
			)
			(layer "F.SilkS")
		)
		(fp_poly
			(pts
				(xy -0.508 0.2794) (xy -0.508 0.2286) (xy -0.635 0.2286) (xy -0.635 -0.254) (xy -0.5334 -0.254)
				(xy -0.5334 -0.2794) (xy 0.5334 -0.2794) (xy 0.5334 -0.254) (xy 0.635 -0.254) (xy 0.635 0.254) (xy 0.5334 0.254)
				(xy 0.5334 0.2794)
			)
			(stroke
				(width 0)
				(type default)
			)
			(fill no)
			(layer "F.CrtYd")
		)
		(pad "1" smd rect
			(at 0.40005 0 270)
			(size 0.4572 0.508)
			(layers "F.Cu" "F.Mask" "F.Paste")
			(net "UART_T6_NODE4_RXD")
		)
		(pad "2" smd rect
			(at -0.40005 0 270)
			(size 0.4572 0.508)
			(layers "F.Cu" "F.Mask" "F.Paste")
			(net "UART_T6_NODE4_RXD_R")
		)
	)
	(footprint ""
		(layer "F.Cu")
		(at 15.21206 -112.127284 -90)
		(property "Reference" "PC63"
			(at 7.979156 -0.13208 0)
			(unlocked yes)
			(layer "F.SilkS")
			(effects
				(font
					(size 0.7874 0.5842)
					(thickness 0.1524)
				)
				(justify left)
			)
		)
		(property "Value" ""
			(at 0 0 270)
			(layer "F.Fab")
			(effects
				(font
					(size 1.27 1.27)
				)
			)
		)
		(duplicate_pad_numbers_are_jumpers no)
		(fp_line
			(start -2.249932 4.533392)
			(end -2.249932 -4.533392)
			(stroke
				(width 0.1524)
				(type default)
			)
			(layer "F.SilkS")
		)
		(fp_line
			(start 2.249932 4.533392)
			(end -2.249932 4.533392)
			(stroke
				(width 0.1524)
				(type default)
			)
			(layer "F.SilkS")
		)
		(fp_line
			(start -2.249932 -4.533392)
			(end 2.249932 -4.533392)
			(stroke
				(width 0.1524)
				(type default)
			)
			(layer "F.SilkS")
		)
		(fp_line
			(start 2.249932 -4.533392)
			(end 2.249932 4.533392)
			(stroke
				(width 0.1524)
				(type default)
			)
			(layer "F.SilkS")
		)
		(fp_poly
			(pts
				(xy 2.326132 -4.533392) (xy 2.326132 -5.39242) (xy -2.326132 -5.39242) (xy -2.326132 -4.533392)
			)
			(stroke
				(width 0)
				(type default)
			)
			(fill yes)
			(layer "F.SilkS")
		)
		(fp_poly
			(pts
				(xy -1.4605 4.457192) (xy -1.4605 3.750056) (xy -2.249932 3.750056) (xy -2.249932 -3.750056) (xy -1.4605 -3.750056)
				(xy -1.4605 -4.457192) (xy 1.4605 -4.457192) (xy 1.4605 -3.750056) (xy 2.249932 -3.750056) (xy 2.249932 3.750056)
				(xy 1.4605 3.750056) (xy 1.4605 4.457192)
			)
			(stroke
				(width 0)
				(type default)
			)
			(fill no)
			(layer "F.CrtYd")
		)
		(fp_line
			(start -2.249932 3.750056)
			(end -2.249932 -3.750056)
			(stroke
				(width 0.1)
				(type default)
			)
			(layer "F.Fab")
		)
		(fp_line
			(start 2.249932 3.750056)
			(end -2.249932 3.750056)
			(stroke
				(width 0.1)
				(type default)
			)
			(layer "F.Fab")
		)
		(fp_line
			(start -2.249932 -3.750056)
			(end 2.249932 -3.750056)
			(stroke
				(width 0.1)
				(type default)
			)
			(layer "F.Fab")
		)
		(fp_line
			(start 2.249932 -3.750056)
			(end 2.249932 3.750056)
			(stroke
				(width 0.1)
				(type default)
			)
			(layer "F.Fab")
		)
		(fp_text user "+"
			(at 2.42062 -6.084062 270)
			(unlocked yes)
			(layer "F.SilkS")
			(effects
				(font
					(size 1.27 0.9652)
					(thickness 0.1524)
				)
				(justify left)
			)
		)
		(fp_text user "+"
			(at -0.786384 -6.322314 270)
			(unlocked yes)
			(layer "F.Fab")
			(effects
				(font
					(size 1.905 1.4224)
					(thickness 0.000001)
				)
				(justify left)
			)
		)
		(pad "1" smd rect
			(at 0 -3.199892 180)
			(size 2.413 2.8194)
			(layers "F.Cu" "F.Mask" "F.Paste")
			(net "P1V05_NODE1")
		)
		(pad "2" smd rect
			(at 0 3.199892 180)
			(size 2.413 2.8194)
			(layers "F.Cu" "F.Mask" "F.Paste")
			(net "GND")
		)
	)
	(footprint ""
		(layer "F.Cu")
		(at 142.910052 -134.19455 180)
		(property "Reference" "R1228"
			(at 3.280918 -3.039364 0)
			(unlocked yes)
			(layer "F.SilkS")
			(effects
				(font
					(size 0.7874 0.5842)
					(thickness 0.1524)
				)
				(justify left)
			)
		)
		(property "Value" ""
			(at 0 0 180)
			(layer "F.Fab")
			(effects
				(font
					(size 1.27 1.27)
				)
			)
		)
		(duplicate_pad_numbers_are_jumpers no)
		(fp_line
			(start 0.7874 0.4064)
			(end -0.7874 0.4064)
			(stroke
				(width 0.1524)
				(type default)
			)
			(layer "F.SilkS")
		)
		(fp_line
			(start 0.7874 -0.4064)
			(end 0.7874 0.4064)
			(stroke
				(width 0.1524)
				(type default)
			)
			(layer "F.SilkS")
		)
		(fp_line
			(start -0.7874 0.4064)
			(end -0.7874 -0.4064)
			(stroke
				(width 0.1524)
				(type default)
			)
			(layer "F.SilkS")
		)
		(fp_line
			(start -0.7874 -0.4064)
			(end 0.7874 -0.4064)
			(stroke
				(width 0.1524)
				(type default)
			)
			(layer "F.SilkS")
		)
		(fp_poly
			(pts
				(xy -0.508 0.2794) (xy -0.508 0.2286) (xy -0.635 0.2286) (xy -0.635 -0.254) (xy -0.5334 -0.254)
				(xy -0.5334 -0.2794) (xy 0.5334 -0.2794) (xy 0.5334 -0.254) (xy 0.635 -0.254) (xy 0.635 0.254) (xy 0.5334 0.254)
				(xy 0.5334 0.2794)
			)
			(stroke
				(width 0)
				(type default)
			)
			(fill no)
			(layer "F.CrtYd")
		)
		(pad "1" smd rect
			(at 0.40005 0 180)
			(size 0.4572 0.508)
			(layers "F.Cu" "F.Mask" "F.Paste")
			(net "PCIE_SW_PRSNT1")
		)
		(pad "2" smd rect
			(at -0.40005 0 180)
			(size 0.4572 0.508)
			(layers "F.Cu" "F.Mask" "F.Paste")
			(net "GND")
		)
	)
	(footprint ""
		(layer "F.Cu")
		(at 113.944654 -46.847252)
		(property "Reference" "R619"
			(at -4.284472 0.187706 0)
			(unlocked yes)
			(layer "F.SilkS")
			(effects
				(font
					(size 0.7874 0.5842)
					(thickness 0.1524)
				)
				(justify left)
			)
		)
		(property "Value" ""
			(at 0 0 0)
			(layer "F.Fab")
			(effects
				(font
					(size 1.27 1.27)
				)
			)
		)
		(duplicate_pad_numbers_are_jumpers no)
		(fp_line
			(start -0.7874 -0.4064)
			(end 0.7874 -0.4064)
			(stroke
				(width 0.1524)
				(type default)
			)
			(layer "F.SilkS")
		)
		(fp_line
			(start -0.7874 0.4064)
			(end -0.7874 -0.4064)
			(stroke
				(width 0.1524)
				(type default)
			)
			(layer "F.SilkS")
		)
		(fp_line
			(start 0.7874 -0.4064)
			(end 0.7874 0.4064)
			(stroke
				(width 0.1524)
				(type default)
			)
			(layer "F.SilkS")
		)
		(fp_line
			(start 0.7874 0.4064)
			(end -0.7874 0.4064)
			(stroke
				(width 0.1524)
				(type default)
			)
			(layer "F.SilkS")
		)
		(fp_poly
			(pts
				(xy -0.508 0.2794) (xy -0.508 0.2286) (xy -0.635 0.2286) (xy -0.635 -0.254) (xy -0.5334 -0.254)
				(xy -0.5334 -0.2794) (xy 0.5334 -0.2794) (xy 0.5334 -0.254) (xy 0.635 -0.254) (xy 0.635 0.254) (xy 0.5334 0.254)
				(xy 0.5334 0.2794)
			)
			(stroke
				(width 0)
				(type default)
			)
			(fill no)
			(layer "F.CrtYd")
		)
		(pad "1" smd rect
			(at 0.40005 0)
			(size 0.4572 0.508)
			(layers "F.Cu" "F.Mask" "F.Paste")
			(net "P3V3_NODE1")
		)
		(pad "2" smd rect
			(at -0.40005 0)
			(size 0.4572 0.508)
			(layers "F.Cu" "F.Mask" "F.Paste")
			(net "N21550241")
		)
	)
	(footprint ""
		(layer "F.Cu")
		(at 156.779468 -173.004988 -90)
		(property "Reference" "C913"
			(at 1.112266 -1.232662 90)
			(unlocked yes)
			(layer "F.SilkS")
			(effects
				(font
					(size 0.7874 0.5842)
					(thickness 0.1524)
				)
				(justify left)
			)
		)
		(property "Value" ""
			(at 0 0 270)
			(layer "F.Fab")
			(effects
				(font
					(size 1.27 1.27)
				)
			)
		)
		(duplicate_pad_numbers_are_jumpers no)
		(fp_line
			(start -0.7874 0.4064)
			(end -0.7874 -0.4064)
			(stroke
				(width 0.1524)
				(type default)
			)
			(layer "F.SilkS")
		)
		(fp_line
			(start 0.7874 0.4064)
			(end -0.7874 0.4064)
			(stroke
				(width 0.1524)
				(type default)
			)
			(layer "F.SilkS")
		)
		(fp_line
			(start 0 0.381)
			(end 0 -0.381)
			(stroke
				(width 0.1524)
				(type default)
			)
			(layer "F.SilkS")
		)
		(fp_line
			(start -0.7874 -0.4064)
			(end 0.7874 -0.4064)
			(stroke
				(width 0.1524)
				(type default)
			)
			(layer "F.SilkS")
		)
		(fp_line
			(start 0.7874 -0.4064)
			(end 0.7874 0.4064)
			(stroke
				(width 0.1524)
				(type default)
			)
			(layer "F.SilkS")
		)
		(fp_poly
			(pts
				(xy -0.5334 0.254) (xy -0.635 0.254) (xy -0.635 0.2286) (xy -0.635 -0.254) (xy -0.5334 -0.254) (xy -0.5334 -0.2794)
				(xy 0.5334 -0.2794) (xy 0.5334 -0.254) (xy 0.635 -0.254) (xy 0.635 0.254) (xy 0.5334 0.254) (xy 0.5334 0.2794)
				(xy -0.508 0.2794) (xy -0.5334 0.2794)
			)
			(stroke
				(width 0)
				(type default)
			)
			(fill no)
			(layer "F.CrtYd")
		)
		(pad "1" smd rect
			(at 0.40005 0 270)
			(size 0.4572 0.508)
			(layers "F.Cu" "F.Mask" "F.Paste")
			(net "P3V3_NODE1")
		)
		(pad "2" smd rect
			(at -0.40005 0 270)
			(size 0.4572 0.508)
			(layers "F.Cu" "F.Mask" "F.Paste")
			(net "GND")
		)
	)
	(footprint ""
		(layer "F.Cu")
		(at 59.260486 -118.910862 90)
		(property "Reference" "R341"
			(at -5.140706 0.82804 90)
			(unlocked yes)
			(layer "F.SilkS")
			(effects
				(font
					(size 0.7874 0.5842)
					(thickness 0.1524)
				)
				(justify left)
			)
		)
		(property "Value" ""
			(at 0 0 90)
			(layer "F.Fab")
			(effects
				(font
					(size 1.27 1.27)
				)
			)
		)
		(duplicate_pad_numbers_are_jumpers no)
		(fp_line
			(start 0.7874 -0.4064)
			(end 0.7874 0.4064)
			(stroke
				(width 0.1524)
				(type default)
			)
			(layer "F.SilkS")
		)
		(fp_line
			(start -0.7874 -0.4064)
			(end 0.7874 -0.4064)
			(stroke
				(width 0.1524)
				(type default)
			)
			(layer "F.SilkS")
		)
		(fp_line
			(start 0.7874 0.4064)
			(end -0.7874 0.4064)
			(stroke
				(width 0.1524)
				(type default)
			)
			(layer "F.SilkS")
		)
		(fp_line
			(start -0.7874 0.4064)
			(end -0.7874 -0.4064)
			(stroke
				(width 0.1524)
				(type default)
			)
			(layer "F.SilkS")
		)
		(fp_poly
			(pts
				(xy -0.508 0.2794) (xy -0.508 0.2286) (xy -0.635 0.2286) (xy -0.635 -0.254) (xy -0.5334 -0.254)
				(xy -0.5334 -0.2794) (xy 0.5334 -0.2794) (xy 0.5334 -0.254) (xy 0.635 -0.254) (xy 0.635 0.254) (xy 0.5334 0.254)
				(xy 0.5334 0.2794)
			)
			(stroke
				(width 0)
				(type default)
			)
			(fill no)
			(layer "F.CrtYd")
		)
		(pad "1" smd rect
			(at 0.40005 0 90)
			(size 0.4572 0.508)
			(layers "F.Cu" "F.Mask" "F.Paste")
			(net "P3V3_NODE1")
		)
		(pad "2" smd rect
			(at -0.40005 0 90)
			(size 0.4572 0.508)
			(layers "F.Cu" "F.Mask" "F.Paste")
			(net "BMC_ROMD1")
		)
	)
	(footprint ""
		(layer "F.Cu")
		(at 145.07845 -51.671474 -90)
		(property "Reference" "R629"
			(at -16.205708 -29.039566 90)
			(unlocked yes)
			(layer "F.SilkS")
			(effects
				(font
					(size 0.7874 0.5842)
					(thickness 0.1524)
				)
				(justify left)
			)
		)
		(property "Value" ""
			(at 0 0 270)
			(layer "F.Fab")
			(effects
				(font
					(size 1.27 1.27)
				)
			)
		)
		(duplicate_pad_numbers_are_jumpers no)
		(fp_line
			(start -1.905 0.8636)
			(end -1.905 -0.8636)
			(stroke
				(width 0.1524)
				(type default)
			)
			(layer "F.SilkS")
		)
		(fp_line
			(start 1.905 0.8636)
			(end -1.905 0.8636)
			(stroke
				(width 0.1524)
				(type default)
			)
			(layer "F.SilkS")
		)
		(fp_line
			(start -1.905 -0.8636)
			(end 1.905 -0.8636)
			(stroke
				(width 0.1524)
				(type default)
			)
			(layer "F.SilkS")
		)
		(fp_line
			(start 1.905 -0.8636)
			(end 1.905 0.8636)
			(stroke
				(width 0.1524)
				(type default)
			)
			(layer "F.SilkS")
		)
		(fp_poly
			(pts
				(xy 1.524 0.6858) (xy 1.524 -0.6858) (xy 1.524 -0.7366) (xy -1.524 -0.7366) (xy -1.524 -0.6858)
				(xy -1.524 0.6858) (xy -1.524 0.7366) (xy 1.524 0.7366)
			)
			(stroke
				(width 0)
				(type default)
			)
			(fill no)
			(layer "F.CrtYd")
		)
		(pad "1" smd rect
			(at 0.94996 0 270)
			(size 1.1176 1.3716)
			(layers "F.Cu" "F.Mask" "F.Paste")
			(net "P5V_NODE1")
		)
		(pad "2" smd rect
			(at -0.94996 0 270)
			(size 1.1176 1.3716)
			(layers "F.Cu" "F.Mask" "F.Paste")
			(net "SATA_P7")
		)
	)
	(footprint ""
		(layer "F.Cu")
		(at 51.67376 -185.205624 90)
		(property "Reference" "R833"
			(at 4.006088 0.055372 90)
			(unlocked yes)
			(layer "F.SilkS")
			(effects
				(font
					(size 0.7874 0.5842)
					(thickness 0.1524)
				)
				(justify left)
			)
		)
		(property "Value" ""
			(at 0 0 90)
			(layer "F.Fab")
			(effects
				(font
					(size 1.27 1.27)
				)
			)
		)
		(duplicate_pad_numbers_are_jumpers no)
		(fp_line
			(start 0.7874 -0.4064)
			(end 0.7874 0.4064)
			(stroke
				(width 0.1524)
				(type default)
			)
			(layer "F.SilkS")
		)
		(fp_line
			(start -0.7874 -0.4064)
			(end 0.7874 -0.4064)
			(stroke
				(width 0.1524)
				(type default)
			)
			(layer "F.SilkS")
		)
		(fp_line
			(start 0.7874 0.4064)
			(end -0.7874 0.4064)
			(stroke
				(width 0.1524)
				(type default)
			)
			(layer "F.SilkS")
		)
		(fp_line
			(start -0.7874 0.4064)
			(end -0.7874 -0.4064)
			(stroke
				(width 0.1524)
				(type default)
			)
			(layer "F.SilkS")
		)
		(fp_poly
			(pts
				(xy -0.508 0.2794) (xy -0.508 0.2286) (xy -0.635 0.2286) (xy -0.635 -0.254) (xy -0.5334 -0.254)
				(xy -0.5334 -0.2794) (xy 0.5334 -0.2794) (xy 0.5334 -0.254) (xy 0.635 -0.254) (xy 0.635 0.254) (xy 0.5334 0.254)
				(xy 0.5334 0.2794)
			)
			(stroke
				(width 0)
				(type default)
			)
			(fill no)
			(layer "F.CrtYd")
		)
		(pad "1" smd rect
			(at 0.40005 0 90)
			(size 0.4572 0.508)
			(layers "F.Cu" "F.Mask" "F.Paste")
			(net "PSU2_AC_OK_R")
		)
		(pad "2" smd rect
			(at -0.40005 0 90)
			(size 0.4572 0.508)
			(layers "F.Cu" "F.Mask" "F.Paste")
			(net "PSU2_AC_OK")
		)
	)
	(footprint ""
		(layer "F.Cu")
		(at 73.337166 -96.709992 -90)
		(property "Reference" "R109"
			(at 54.98719 -28.313888 90)
			(unlocked yes)
			(layer "F.SilkS")
			(effects
				(font
					(size 0.7874 0.5842)
					(thickness 0.1524)
				)
				(justify left)
			)
		)
		(property "Value" ""
			(at 0 0 270)
			(layer "F.Fab")
			(effects
				(font
					(size 1.27 1.27)
				)
			)
		)
		(duplicate_pad_numbers_are_jumpers no)
		(fp_line
			(start -0.7874 0.4064)
			(end -0.7874 -0.4064)
			(stroke
				(width 0.1524)
				(type default)
			)
			(layer "F.SilkS")
		)
		(fp_line
			(start 0.7874 0.4064)
			(end -0.7874 0.4064)
			(stroke
				(width 0.1524)
				(type default)
			)
			(layer "F.SilkS")
		)
		(fp_line
			(start -0.7874 -0.4064)
			(end 0.7874 -0.4064)
			(stroke
				(width 0.1524)
				(type default)
			)
			(layer "F.SilkS")
		)
		(fp_line
			(start 0.7874 -0.4064)
			(end 0.7874 0.4064)
			(stroke
				(width 0.1524)
				(type default)
			)
			(layer "F.SilkS")
		)
		(fp_poly
			(pts
				(xy -0.508 0.2794) (xy -0.508 0.2286) (xy -0.635 0.2286) (xy -0.635 -0.254) (xy -0.5334 -0.254)
				(xy -0.5334 -0.2794) (xy 0.5334 -0.2794) (xy 0.5334 -0.254) (xy 0.635 -0.254) (xy 0.635 0.254) (xy 0.5334 0.254)
				(xy 0.5334 0.2794)
			)
			(stroke
				(width 0)
				(type default)
			)
			(fill no)
			(layer "F.CrtYd")
		)
		(pad "1" smd rect
			(at 0.40005 0 270)
			(size 0.4572 0.508)
			(layers "F.Cu" "F.Mask" "F.Paste")
			(net "H_CPU_NODE1_ERR1_R")
		)
		(pad "2" smd rect
			(at -0.40005 0 270)
			(size 0.4572 0.508)
			(layers "F.Cu" "F.Mask" "F.Paste")
			(net "P3V3_NODE1")
		)
	)
)
